# BASEBOARD_FAB2 (Tioga Pass) — schematic netlist excerpt (pin names and nets, part order shuffled) for the footprints in the layout excerpt that follows; sources: Cadence DE-HDL packaged netlist, KiCad conversion of Wiwynn_Tioga_Pass_MB.brd

C9N8  CAP  0.22UF 16V 10% X7R  pkg 0402  page 182 : A = P3E_CPU1_PE3_MP_C_TXN<14> ; B = P3E_CPU1_PE3_MP_TXN<14>
C3L25  CAP_A  22.0UF 4V 20% X6S  pkg 0603V  page 132 : A = PVNN_PCH_STBY ; B = GND
C25W13  CAP_A  0.1UF 16V 10% X7R  pkg 0402V  page 151 : A = BMC_M_VREFCA ; B = GND

(kicad_pcb
	(version 20260206)
	(generator "pcbnew")
	(generator_version "10.0")
	(general
		(thickness 1.6)
		(legacy_teardrops no)
	)
	(paper "A4")
	(title_block
		(title "Wiwynn_Tioga_Pass_MB.brd")
		(comment 1 "Tioga Pass / footprints 2920-2922 of 4770")
	)
	(layers
		(0 "F.Cu" signal "TOP")
		(4 "In1.Cu" signal "L2GND")
		(6 "In2.Cu" signal "L3")
		(8 "In3.Cu" signal "L4GND")
		(10 "In4.Cu" signal "L5")
		(12 "In5.Cu" signal "L6GND")
		(14 "In6.Cu" signal "L7VCC")
		(16 "In7.Cu" signal "L8VCC")
		(18 "In8.Cu" signal "L9GND")
		(20 "In9.Cu" signal "L10")
		(22 "In10.Cu" signal "L11GND")
		(24 "In11.Cu" signal "L12")
		(26 "In12.Cu" signal "L13GND")
		(2 "B.Cu" signal "BOTTOM")
		(9 "F.Adhes" user "F.Adhesive")
		(11 "B.Adhes" user "B.Adhesive")
		(13 "F.Paste" user "Package Geometry/Pastemask Top")
		(15 "B.Paste" user "Package Geometry/Pastemask Bottom")
		(5 "F.SilkS" user "Ref Des/Silkscreen Top")
		(7 "B.SilkS" user "Ref Des/Silkscreen Bottom")
		(1 "F.Mask" user "Board Geometry/Soldermask Top")
		(3 "B.Mask" user "Board Geometry/Soldermask Bottom")
		(17 "Dwgs.User" user "User.Drawings")
		(19 "Cmts.User" user "User.Comments")
		(21 "Eco1.User" user "User.Eco1")
		(23 "Eco2.User" user "User.Eco2")
		(25 "Edge.Cuts" user "Board Geometry/Outline")
		(27 "Margin" user)
		(31 "F.CrtYd" user "Package Geometry/Place Bound Top")
		(29 "B.CrtYd" user "Package Geometry/Place Bound Bottom")
		(35 "F.Fab" user "Ref Des/Assembly Top")
		(33 "B.Fab" user "Ref Des/Assembly Bottom")
	)
	(footprint ""
		(layer "B.Cu")
		(at 12.40282 -102.46868 90)
		(property "Reference" "C9N8"
			(at 0 0 90)
			(layer "B.SilkS")
			(hide yes)
			(effects
				(font
					(size 1.27 1.27)
				)
				(justify mirror)
			)
		)
		(property "Value" ""
			(at 0 0 90)
			(layer "B.Fab")
			(effects
				(font
					(size 1.27 1.27)
				)
				(justify mirror)
			)
		)
		(duplicate_pad_numbers_are_jumpers no)
		(fp_poly
			(pts
				(xy -0.3048 -0.1016) (xy -0.3048 0.9906) (xy 0.3048 0.9906) (xy 0.3048 -0.1016)
			)
			(stroke
				(width 0)
				(type default)
			)
			(fill no)
			(layer "B.CrtYd")
		)
		(fp_line
			(start 0.3048 -0.1016)
			(end 0.3048 0.9906)
			(stroke
				(width 0.1)
				(type default)
			)
			(layer "B.Fab")
		)
		(fp_line
			(start -0.3048 -0.1016)
			(end 0.3048 -0.1016)
			(stroke
				(width 0.1)
				(type default)
			)
			(layer "B.Fab")
		)
		(fp_line
			(start 0.3048 0.9906)
			(end -0.3048 0.9906)
			(stroke
				(width 0.1)
				(type default)
			)
			(layer "B.Fab")
		)
		(fp_line
			(start -0.3048 0.9906)
			(end -0.3048 -0.1016)
			(stroke
				(width 0.1)
				(type default)
			)
			(layer "B.Fab")
		)
		(pad "1" smd rect
			(at 0 0 270)
			(size 0.508 0.508)
			(layers "B.Cu" "B.Mask" "B.Paste")
			(net "P3E_CPU1_PE3_MP_C_TXN<14>")
		)
		(pad "2" smd rect
			(at 0 0.889 270)
			(size 0.508 0.508)
			(layers "B.Cu" "B.Mask" "B.Paste")
			(net "P3E_CPU1_PE3_MP_TXN<14>")
		)
		(zone
			(layer "B.Cu")
			(hatch none 0.5)
			(connect_pads
				(clearance 0)
			)
			(min_thickness 0.25)
			(keepout
				(tracks allowed)
				(vias not_allowed)
				(pads allowed)
				(copperpour not_allowed)
				(footprints allowed)
			)
			(placement
				(enabled no)
				(sheetname "")
			)
			(fill
				(thermal_gap 0.5)
				(thermal_bridge_width 0.5)
				(island_removal_mode 0)
			)
			(polygon
				(pts
					(xy 12.65682 -102.72268) (xy 12.65682 -102.21468) (xy 13.03782 -102.21468) (xy 13.03782 -102.72268)
				)
			)
		)
		(zone
			(layer "B.Cu")
			(hatch none 0.5)
			(connect_pads
				(clearance 0)
			)
			(min_thickness 0.25)
			(keepout
				(tracks not_allowed)
				(vias allowed)
				(pads allowed)
				(copperpour not_allowed)
				(footprints allowed)
			)
			(placement
				(enabled no)
				(sheetname "")
			)
			(fill
				(thermal_gap 0.5)
				(thermal_bridge_width 0.5)
				(island_removal_mode 0)
			)
			(polygon
				(pts
					(xy 13.03782 -102.72268) (xy 13.03782 -102.21468) (xy 12.65682 -102.21468) (xy 12.65682 -102.72268)
				)
			)
		)
	)
	(footprint ""
		(layer "B.Cu")
		(at 383.4384 -137.541)
		(property "Reference" "C3L25"
			(at 0 0 0)
			(layer "B.SilkS")
			(hide yes)
			(effects
				(font
					(size 1.27 1.27)
				)
				(justify mirror)
			)
		)
		(property "Value" ""
			(at 0 0 0)
			(layer "B.Fab")
			(effects
				(font
					(size 1.27 1.27)
				)
				(justify mirror)
			)
		)
		(duplicate_pad_numbers_are_jumpers no)
		(fp_poly
			(pts
				(xy 0.4953 -0.2032) (xy -0.4953 -0.2032) (xy -0.4953 1.6002) (xy 0.4953 1.6002)
			)
			(stroke
				(width 0)
				(type default)
			)
			(fill no)
			(layer "B.CrtYd")
		)
		(fp_line
			(start -0.4953 -0.2032)
			(end -0.4953 1.6002)
			(stroke
				(width 0.1)
				(type default)
			)
			(layer "B.Fab")
		)
		(fp_line
			(start -0.4953 1.6002)
			(end 0.4953 1.6002)
			(stroke
				(width 0.1)
				(type default)
			)
			(layer "B.Fab")
		)
		(fp_line
			(start 0.4953 -0.2032)
			(end -0.4953 -0.2032)
			(stroke
				(width 0.1)
				(type default)
			)
			(layer "B.Fab")
		)
		(fp_line
			(start 0.4953 1.6002)
			(end 0.4953 -0.2032)
			(stroke
				(width 0.1)
				(type default)
			)
			(layer "B.Fab")
		)
		(pad "1" smd rect
			(at 0 0 180)
			(size 0.762 0.889)
			(layers "B.Cu" "B.Mask" "B.Paste")
			(net "PVNN_PCH_STBY")
		)
		(pad "2" smd rect
			(at 0 1.397 180)
			(size 0.762 0.889)
			(layers "B.Cu" "B.Mask" "B.Paste")
			(net "GND")
		)
		(zone
			(layer "B.Cu")
			(hatch none 0.5)
			(connect_pads
				(clearance 0)
			)
			(min_thickness 0.25)
			(keepout
				(tracks not_allowed)
				(vias allowed)
				(pads allowed)
				(copperpour not_allowed)
				(footprints allowed)
			)
			(placement
				(enabled no)
				(sheetname "")
			)
			(fill
				(thermal_gap 0.5)
				(thermal_bridge_width 0.5)
				(island_removal_mode 0)
			)
			(polygon
				(pts
					(xy 383.8194 -137.0965) (xy 383.0574 -137.0965) (xy 383.0574 -136.5885) (xy 383.8194 -136.5885)
				)
			)
		)
	)
	(footprint ""
		(layer "B.Cu")
		(at 444.09995 -29.6164)
		(property "Reference" "C25W13"
			(at 0.8382 -0.67818 0)
			(unlocked yes)
			(layer "B.SilkS")
			(effects
				(font
					(size 0.4064 0.254)
					(thickness 0.1524)
				)
				(justify left mirror)
			)
		)
		(property "Value" ""
			(at 0 0 0)
			(layer "B.Fab")
			(effects
				(font
					(size 1.27 1.27)
				)
				(justify mirror)
			)
		)
		(duplicate_pad_numbers_are_jumpers no)
		(fp_poly
			(pts
				(xy -0.3048 -0.1016) (xy -0.3048 0.9906) (xy 0.3048 0.9906) (xy 0.3048 -0.1016)
			)
			(stroke
				(width 0)
				(type default)
			)
			(fill no)
			(layer "B.CrtYd")
		)
		(fp_line
			(start -0.3048 -0.1016)
			(end 0.3048 -0.1016)
			(stroke
				(width 0.1)
				(type default)
			)
			(layer "B.Fab")
		)
		(fp_line
			(start -0.3048 0.9906)
			(end -0.3048 -0.1016)
			(stroke
				(width 0.1)
				(type default)
			)
			(layer "B.Fab")
		)
		(fp_line
			(start 0.3048 -0.1016)
			(end 0.3048 0.9906)
			(stroke
				(width 0.1)
				(type default)
			)
			(layer "B.Fab")
		)
		(fp_line
			(start 0.3048 0.9906)
			(end -0.3048 0.9906)
			(stroke
				(width 0.1)
				(type default)
			)
			(layer "B.Fab")
		)
		(pad "1" smd rect
			(at 0 0 180)
			(size 0.508 0.508)
			(layers "B.Cu" "B.Mask" "B.Paste")
			(net "BMC_M_VREFCA")
		)
		(pad "2" smd rect
			(at 0 0.889 180)
			(size 0.508 0.508)
			(layers "B.Cu" "B.Mask" "B.Paste")
			(net "GND")
		)
		(zone
			(layer "B.Cu")
			(hatch none 0.5)
			(connect_pads
				(clearance 0)
			)
			(min_thickness 0.25)
			(keepout
				(tracks allowed)
				(vias not_allowed)
				(pads allowed)
				(copperpour not_allowed)
				(footprints allowed)
			)
			(placement
				(enabled no)
				(sheetname "")
			)
			(fill
				(thermal_gap 0.5)
				(thermal_bridge_width 0.5)
				(island_removal_mode 0)
			)
			(polygon
				(pts
					(xy 444.35395 -29.3624) (xy 443.84595 -29.3624) (xy 443.84595 -28.9814) (xy 444.35395 -28.9814)
				)
			)
		)
		(zone
			(layer "B.Cu")
			(hatch none 0.5)
			(connect_pads
				(clearance 0)
			)
			(min_thickness 0.25)
			(keepout
				(tracks not_allowed)
				(vias allowed)
				(pads allowed)
				(copperpour not_allowed)
				(footprints allowed)
			)
			(placement
				(enabled no)
				(sheetname "")
			)
			(fill
				(thermal_gap 0.5)
				(thermal_bridge_width 0.5)
				(island_removal_mode 0)
			)
			(polygon
				(pts
					(xy 444.35395 -28.9814) (xy 443.84595 -28.9814) (xy 443.84595 -29.3624) (xy 444.35395 -29.3624)
				)
			)
		)
	)
)
